(kicad_pcb
	(version 20260206)
	(generator "pcbnew")
	(generator_version "10.0")
	(general
		(thickness 1.6)
		(legacy_teardrops no)
	)
	(paper "A4")
	(title_block
		(title "Bryce Canyon_R.DPB_16317-1_OCP.brd")
		(comment 1 "Bryce Canyon / footprints 2061-2069 of 2099")
	)
	(layers
		(0 "F.Cu" signal "TOP")
		(4 "In1.Cu" signal "L2GND")
		(6 "In2.Cu" signal "L3")
		(8 "In3.Cu" signal "L4VCC")
		(10 "In4.Cu" signal "L5VCC")
		(12 "In5.Cu" signal "L6")
		(14 "In6.Cu" signal "L7GND")
		(2 "B.Cu" signal "BOTTOM")
		(9 "F.Adhes" user "F.Adhesive")
		(11 "B.Adhes" user "B.Adhesive")
		(13 "F.Paste" user "Package Geometry/Pastemask Top")
		(15 "B.Paste" user "Package Geometry/Pastemask Bottom")
		(5 "F.SilkS" user "Ref Des/Silkscreen Top")
		(7 "B.SilkS" user "Ref Des/Silkscreen Bottom")
		(1 "F.Mask" user "Board Geometry/Soldermask Top")
		(3 "B.Mask" user "Board Geometry/Soldermask Bottom")
		(17 "Dwgs.User" user "User.Drawings")
		(19 "Cmts.User" user "User.Comments")
		(21 "Eco1.User" user "User.Eco1")
		(23 "Eco2.User" user "User.Eco2")
		(25 "Edge.Cuts" user "Board Geometry/Outline")
		(27 "Margin" user)
		(31 "F.CrtYd" user "Package Geometry/Place Bound Top")
		(29 "B.CrtYd" user "Package Geometry/Place Bound Bottom")
		(35 "F.Fab" user "Ref Des/Assembly Top")
		(33 "B.Fab" user "Ref Des/Assembly Bottom")
	)
	(footprint ""
		(layer "B.Cu")
		(at 259.82549 -286.582612)
		(property "Reference" "C692"
			(at 0 0 0)
			(layer "B.SilkS")
			(hide yes)
			(effects
				(font
					(size 1.27 1.27)
				)
				(justify mirror)
			)
		)
		(property "Value" "SC100P50V2JN-3GP"
			(at -1.1811 -2.7051 0)
			(unlocked yes)
			(layer "B.Fab")
			(hide yes)
			(effects
				(font
					(size 1.016 1.016)
					(thickness 0.1524)
				)
				(justify mirror)
			)
		)
		(property "Device Type" "C402H22"
			(at -1.1811 -4.2291 0)
			(unlocked yes)
			(layer "B.Fab")
			(hide yes)
			(effects
				(font
					(size 1.016 1.016)
					(thickness 0.1524)
				)
				(justify mirror)
			)
		)
		(duplicate_pad_numbers_are_jumpers no)
		(fp_rect
			(start 0.4318 0.9525)
			(end -0.4318 -0.9525)
			(stroke
				(width 0)
				(type default)
			)
			(fill no)
			(layer "B.CrtYd")
		)
		(fp_rect
			(start 0.4318 0.9525)
			(end -0.4318 -0.9525)
			(stroke
				(width 0)
				(type default)
			)
			(fill no)
			(layer "B.Fab")
		)
		(pad "1" smd custom
			(at 0 -0.4445 180)
			(size 0.1524 0.1524)
			(layers "B.Cu" "B.Mask" "B.Paste")
			(net "P3V3_STBY_CC_R")
			(options
				(clearance outline)
				(anchor circle)
			)
			(primitives
				(gr_poly
					(pts
						(arc
							(start 0.3048 0.2032)
							(mid 0.275042 0.275042)
							(end 0.2032 0.3048)
						)
						(arc
							(start -0.2032 0.3048)
							(mid -0.275042 0.275042)
							(end -0.3048 0.2032)
						)
						(arc
							(start -0.3048 -0.2032)
							(mid -0.275042 -0.275042)
							(end -0.2032 -0.3048)
						)
						(arc
							(start 0.2032 -0.3048)
							(mid 0.275042 -0.275042)
							(end 0.3048 -0.2032)
						)
					)
					(width 0)
					(fill yes)
				)
			)
		)
		(pad "2" smd custom
			(at 0 0.4445 180)
			(size 0.1524 0.1524)
			(layers "B.Cu" "B.Mask" "B.Paste")
			(net "P3V3_STBY_VFB")
			(options
				(clearance outline)
				(anchor circle)
			)
			(primitives
				(gr_poly
					(pts
						(arc
							(start 0.3048 0.2032)
							(mid 0.275042 0.275042)
							(end 0.2032 0.3048)
						)
						(arc
							(start -0.2032 0.3048)
							(mid -0.275042 0.275042)
							(end -0.3048 0.2032)
						)
						(arc
							(start -0.3048 -0.2032)
							(mid -0.275042 -0.275042)
							(end -0.2032 -0.3048)
						)
						(arc
							(start 0.2032 -0.3048)
							(mid 0.275042 -0.275042)
							(end 0.3048 -0.2032)
						)
					)
					(width 0)
					(fill yes)
				)
			)
		)
	)
	(footprint ""
		(layer "B.Cu")
		(at 206.756 -348.361 90)
		(property "Reference" "R1019"
			(at 0 0 90)
			(layer "B.SilkS")
			(hide yes)
			(effects
				(font
					(size 1.27 1.27)
				)
				(justify mirror)
			)
		)
		(property "Value" "10R5F-1-GP"
			(at 0 -8.9535 90)
			(unlocked yes)
			(layer "B.Fab")
			(hide yes)
			(effects
				(font
					(size 1.27 1.016)
					(thickness 0.1524)
				)
				(justify mirror)
			)
		)
		(property "Device Type" "R805H24"
			(at 0 -10.6299 90)
			(unlocked yes)
			(layer "B.Fab")
			(hide yes)
			(effects
				(font
					(size 1.27 1.016)
					(thickness 0.1524)
				)
				(justify mirror)
			)
		)
		(duplicate_pad_numbers_are_jumpers no)
		(fp_line
			(start 0.889 -1.7018)
			(end 0.889 0.2794)
			(stroke
				(width 0.1524)
				(type default)
			)
			(layer "B.SilkS")
		)
		(fp_line
			(start -0.889 -1.7018)
			(end 0.889 -1.7018)
			(stroke
				(width 0.1524)
				(type default)
			)
			(layer "B.SilkS")
		)
		(fp_line
			(start -0.889 -1.7018)
			(end -0.889 -0.381)
			(stroke
				(width 0.1524)
				(type default)
			)
			(layer "B.SilkS")
		)
		(fp_line
			(start 0.889 0.0762)
			(end 0.889 1.7018)
			(stroke
				(width 0.1524)
				(type default)
			)
			(layer "B.SilkS")
		)
		(fp_line
			(start 0.889 1.7018)
			(end -0.889 1.7018)
			(stroke
				(width 0.1524)
				(type default)
			)
			(layer "B.SilkS")
		)
		(fp_line
			(start -0.889 1.7018)
			(end -0.889 -0.508)
			(stroke
				(width 0.1524)
				(type default)
			)
			(layer "B.SilkS")
		)
		(fp_poly
			(pts
				(xy -0.9652 -1.778) (xy -0.9652 1.778) (xy 0.9652 1.778) (xy 0.9652 -1.778)
			)
			(stroke
				(width 0)
				(type default)
			)
			(fill no)
			(layer "B.CrtYd")
		)
		(fp_rect
			(start 0.9652 1.778)
			(end -0.9652 -1.778)
			(stroke
				(width 0)
				(type default)
			)
			(fill no)
			(layer "B.Fab")
		)
		(pad "1" smd rect
			(at 0 -0.9652 270)
			(size 1.397 1.143)
			(layers "B.Cu" "B.Mask" "B.Paste")
			(net "MB0_12V_CTRL_GATE5")
		)
		(pad "2" smd rect
			(at 0 0.9652 270)
			(size 1.397 1.143)
			(layers "B.Cu" "B.Mask" "B.Paste")
			(net "MB0_CM_GATE_R")
		)
	)
	(footprint ""
		(layer "B.Cu")
		(at 240.665 -279.8318 -90)
		(property "Reference" "C702"
			(at 0 0 90)
			(layer "B.SilkS")
			(hide yes)
			(effects
				(font
					(size 1.27 1.27)
				)
				(justify mirror)
			)
		)
		(property "Value" "SC10U6D3V5KX-4GP"
			(at 0.0762 -6.1214 270)
			(unlocked yes)
			(layer "B.Fab")
			(hide yes)
			(effects
				(font
					(size 1.016 1.016)
					(thickness 0.1524)
				)
				(justify mirror)
			)
		)
		(property "Device Type" "C805H58"
			(at 0.0762 -8.1534 270)
			(unlocked yes)
			(layer "B.Fab")
			(hide yes)
			(effects
				(font
					(size 1.016 1.016)
					(thickness 0.1524)
				)
				(justify mirror)
			)
		)
		(duplicate_pad_numbers_are_jumpers no)
		(fp_line
			(start -0.635 0)
			(end 0.635 0)
			(stroke
				(width 0.508)
				(type default)
			)
			(layer "B.SilkS")
		)
		(fp_rect
			(start 0.9652 1.778)
			(end -0.9652 -1.778)
			(stroke
				(width 0)
				(type default)
			)
			(fill no)
			(layer "B.CrtYd")
		)
		(fp_poly
			(pts
				(xy 0.9652 -1.778) (xy -0.9652 -1.778) (xy -0.9652 1.778) (xy 0.9652 1.778)
			)
			(stroke
				(width 0)
				(type default)
			)
			(fill no)
			(layer "B.Fab")
		)
		(pad "1" smd rect
			(at 0 -0.9652 90)
			(size 1.397 1.143)
			(layers "B.Cu" "B.Mask" "B.Paste")
			(net "P3V3_STBY_B")
		)
		(pad "2" smd rect
			(at 0 0.9652 90)
			(size 1.397 1.143)
			(layers "B.Cu" "B.Mask" "B.Paste")
			(net "GND")
		)
	)
	(footprint ""
		(layer "B.Cu")
		(at 131.292092 -364.927134)
		(property "Reference" "R966"
			(at 0 0 0)
			(layer "B.SilkS")
			(hide yes)
			(effects
				(font
					(size 1.27 1.27)
				)
				(justify mirror)
			)
		)
		(property "Value" "4K7R2J-2-GP"
			(at -0.064008 -3.993896 0)
			(unlocked yes)
			(layer "B.Fab")
			(hide yes)
			(effects
				(font
					(size 1.016 1.016)
					(thickness 0.1524)
				)
				(justify mirror)
			)
		)
		(property "Device Type" "R402H16"
			(at -0.064008 -5.517896 0)
			(unlocked yes)
			(layer "B.Fab")
			(hide yes)
			(effects
				(font
					(size 1.016 1.016)
					(thickness 0.1524)
				)
				(justify mirror)
			)
		)
		(duplicate_pad_numbers_are_jumpers no)
		(fp_line
			(start -0.508 -0.9398)
			(end 0.508 -0.9398)
			(stroke
				(width 0.1524)
				(type default)
			)
			(layer "B.SilkS")
		)
		(fp_line
			(start 0.508 -0.9398)
			(end 0.508 0.9398)
			(stroke
				(width 0.1524)
				(type default)
			)
			(layer "B.SilkS")
		)
		(fp_rect
			(start 0.508 0.9398)
			(end -0.508 -0.9398)
			(stroke
				(width 0)
				(type default)
			)
			(fill no)
			(layer "B.CrtYd")
		)
		(fp_rect
			(start 0.508 0.9398)
			(end -0.508 -0.9398)
			(stroke
				(width 0)
				(type default)
			)
			(fill no)
			(layer "B.Fab")
		)
		(pad "1" smd custom
			(at 0 -0.4445 180)
			(size 0.1397 0.1397)
			(layers "B.Cu" "B.Mask" "B.Paste")
			(net "P12V_IN")
			(options
				(clearance outline)
				(anchor circle)
			)
			(primitives
				(gr_poly
					(pts
						(arc
							(start -0.1778 0.2794)
							(mid -0.249642 0.249642)
							(end -0.2794 0.1778)
						)
						(arc
							(start -0.2794 -0.1778)
							(mid -0.249642 -0.249642)
							(end -0.1778 -0.2794)
						)
						(arc
							(start 0.1778 -0.2794)
							(mid 0.249642 -0.249642)
							(end 0.2794 -0.1778)
						)
						(arc
							(start 0.2794 0.1778)
							(mid 0.249642 0.249642)
							(end 0.1778 0.2794)
						)
					)
					(width 0)
					(fill yes)
				)
			)
		)
		(pad "2" smd custom
			(at 0 0.4445 180)
			(size 0.1397 0.1397)
			(layers "B.Cu" "B.Mask" "B.Paste")
			(net "GATE_FAN1")
			(options
				(clearance outline)
				(anchor circle)
			)
			(primitives
				(gr_poly
					(pts
						(arc
							(start -0.1778 0.2794)
							(mid -0.249642 0.249642)
							(end -0.2794 0.1778)
						)
						(arc
							(start -0.2794 -0.1778)
							(mid -0.249642 -0.249642)
							(end -0.1778 -0.2794)
						)
						(arc
							(start 0.1778 -0.2794)
							(mid 0.249642 -0.249642)
							(end 0.2794 -0.1778)
						)
						(arc
							(start 0.2794 0.1778)
							(mid 0.249642 0.249642)
							(end 0.1778 0.2794)
						)
					)
					(width 0)
					(fill yes)
				)
			)
		)
	)
	(footprint ""
		(layer "B.Cu")
		(at 425.174918 -66.799968)
		(property "Reference" "SCW2"
			(at 0 0 0)
			(layer "B.SilkS")
			(hide yes)
			(effects
				(font
					(size 1.27 1.27)
				)
				(justify mirror)
			)
		)
		(property "Value" ""
			(at 0 0 0)
			(layer "B.Fab")
			(effects
				(font
					(size 1.27 1.27)
				)
				(justify mirror)
			)
		)
		(duplicate_pad_numbers_are_jumpers no)
		(fp_poly
			(pts
				(arc
					(start 5.4356 0)
					(mid -5.4356 0)
					(end 5.4356 0)
				)
			)
			(stroke
				(width 0)
				(type default)
			)
			(fill no)
			(layer "B.CrtYd")
		)
		(fp_poly
			(pts
				(arc
					(start 5.4356 0)
					(mid -5.4356 0)
					(end 5.4356 0)
				)
			)
			(stroke
				(width 0)
				(type default)
			)
			(fill no)
			(layer "F.CrtYd")
		)
		(fp_poly
			(pts
				(arc
					(start 5.4356 0)
					(mid -5.4356 0)
					(end 5.4356 0)
				)
			)
			(stroke
				(width 0)
				(type default)
			)
			(fill no)
			(layer "B.Fab")
		)
		(fp_poly
			(pts
				(arc
					(start 5.4356 0)
					(mid -5.4356 0)
					(end 5.4356 0)
				)
			)
			(stroke
				(width 0)
				(type default)
			)
			(fill no)
			(layer "F.Fab")
		)
		(pad "" np_thru_hole circle
			(at 0 0 180)
			(size 0.254 0.254)
			(drill 10.2616)
			(layers "*.Cu" "*.Mask")
			(clearance 5.3594)
			(thermal_gap 5.3594)
		)
		(zone
			(layers "F.Cu" "B.Cu" "In1.Cu" "In2.Cu" "In3.Cu" "In4.Cu" "In5.Cu" "In6.Cu")
			(hatch none 0.5)
			(connect_pads
				(clearance 0)
			)
			(min_thickness 0.25)
			(keepout
				(tracks not_allowed)
				(vias allowed)
				(pads allowed)
				(copperpour not_allowed)
				(footprints allowed)
			)
			(placement
				(enabled no)
				(sheetname "")
			)
			(fill
				(thermal_gap 0.5)
				(thermal_bridge_width 0.5)
				(island_removal_mode 0)
			)
			(polygon
				(pts
					(arc
						(start 430.610518 -66.799968)
						(mid 419.739318 -66.799968)
						(end 430.610518 -66.799968)
					)
				)
			)
		)
	)
	(footprint ""
		(layer "B.Cu")
		(at 52.032662 -118.44147 -90)
		(property "Reference" "R1125"
			(at 0 0 90)
			(layer "B.SilkS")
			(hide yes)
			(effects
				(font
					(size 1.27 1.27)
				)
				(justify mirror)
			)
		)
		(property "Value" "10R3F-GP"
			(at 0.0254 -2.5146 270)
			(unlocked yes)
			(layer "B.Fab")
			(hide yes)
			(effects
				(font
					(size 1.016 1.016)
					(thickness 0.1524)
				)
				(justify mirror)
			)
		)
		(property "Device Type" "R603H22"
			(at 0.0254 -4.0386 270)
			(unlocked yes)
			(layer "B.Fab")
			(hide yes)
			(effects
				(font
					(size 1.016 1.016)
					(thickness 0.1524)
				)
				(justify mirror)
			)
		)
		(duplicate_pad_numbers_are_jumpers no)
		(fp_line
			(start -0.2032 0)
			(end -0.4826 0)
			(stroke
				(width 0.2032)
				(type default)
			)
			(layer "B.SilkS")
		)
		(fp_line
			(start 0.4826 0)
			(end 0.2032 0)
			(stroke
				(width 0.2032)
				(type default)
			)
			(layer "B.SilkS")
		)
		(fp_rect
			(start 0.5842 1.3335)
			(end -0.5842 -1.3335)
			(stroke
				(width 0)
				(type default)
			)
			(fill no)
			(layer "B.CrtYd")
		)
		(fp_rect
			(start 0.5842 1.3335)
			(end -0.5842 -1.3335)
			(stroke
				(width 0)
				(type default)
			)
			(fill no)
			(layer "B.Fab")
		)
		(pad "1" smd custom
			(at 0 -0.762 90)
			(size 0.2159 0.2159)
			(layers "B.Cu" "B.Mask" "B.Paste")
			(net "P5V_B_2_CC")
			(options
				(clearance outline)
				(anchor circle)
			)
			(primitives
				(gr_poly
					(pts
						(arc
							(start -0.3302 0.4318)
							(mid -0.402042 0.402042)
							(end -0.4318 0.3302)
						)
						(arc
							(start -0.4318 -0.3302)
							(mid -0.402042 -0.402042)
							(end -0.3302 -0.4318)
						)
						(arc
							(start 0.3302 -0.4318)
							(mid 0.402042 -0.402042)
							(end 0.4318 -0.3302)
						)
						(arc
							(start 0.4318 0.3302)
							(mid 0.402042 0.402042)
							(end 0.3302 0.4318)
						)
					)
					(width 0)
					(fill yes)
				)
			)
		)
		(pad "2" smd custom
			(at 0 0.762 90)
			(size 0.2159 0.2159)
			(layers "B.Cu" "B.Mask" "B.Paste")
			(net "P5V_B_2_VFB_R")
			(options
				(clearance outline)
				(anchor circle)
			)
			(primitives
				(gr_poly
					(pts
						(arc
							(start -0.3302 0.4318)
							(mid -0.402042 0.402042)
							(end -0.4318 0.3302)
						)
						(arc
							(start -0.4318 -0.3302)
							(mid -0.402042 -0.402042)
							(end -0.3302 -0.4318)
						)
						(arc
							(start 0.3302 -0.4318)
							(mid 0.402042 -0.402042)
							(end 0.4318 -0.3302)
						)
						(arc
							(start 0.4318 0.3302)
							(mid 0.402042 0.402042)
							(end 0.3302 0.4318)
						)
					)
					(width 0)
					(fill yes)
				)
			)
		)
	)
	(footprint ""
		(layer "B.Cu")
		(at 14.417802 -223.01835 180)
		(property "Reference" "C617"
			(at 0 0 0)
			(layer "B.SilkS")
			(hide yes)
			(effects
				(font
					(size 1.27 1.27)
				)
				(justify mirror)
			)
		)
		(property "Value" "SC10U16V5KX-7-GP-U"
			(at 0.0762 -6.1214 180)
			(unlocked yes)
			(layer "B.Fab")
			(hide yes)
			(effects
				(font
					(size 1.016 1.016)
					(thickness 0.1524)
				)
				(justify mirror)
			)
		)
		(property "Device Type" "C805H58"
			(at 0.0762 -8.1534 180)
			(unlocked yes)
			(layer "B.Fab")
			(hide yes)
			(effects
				(font
					(size 1.016 1.016)
					(thickness 0.1524)
				)
				(justify mirror)
			)
		)
		(duplicate_pad_numbers_are_jumpers no)
		(fp_line
			(start -0.635 0)
			(end 0.635 0)
			(stroke
				(width 0.508)
				(type default)
			)
			(layer "B.SilkS")
		)
		(fp_rect
			(start 0.9652 1.778)
			(end -0.9652 -1.778)
			(stroke
				(width 0)
				(type default)
			)
			(fill no)
			(layer "B.CrtYd")
		)
		(fp_poly
			(pts
				(xy 0.9652 -1.778) (xy -0.9652 -1.778) (xy -0.9652 1.778) (xy 0.9652 1.778)
			)
			(stroke
				(width 0)
				(type default)
			)
			(fill no)
			(layer "B.Fab")
		)
		(pad "1" smd rect
			(at 0 -0.9652)
			(size 1.397 1.143)
			(layers "B.Cu" "B.Mask" "B.Paste")
			(net "P12V_B_1_VIN_U31")
		)
		(pad "2" smd rect
			(at 0 0.9652)
			(size 1.397 1.143)
			(layers "B.Cu" "B.Mask" "B.Paste")
			(net "GND")
		)
	)
	(footprint ""
		(layer "B.Cu")
		(at 427.065186 -112.701578 180)
		(property "Reference" "C673"
			(at 0 0 0)
			(layer "B.SilkS")
			(hide yes)
			(effects
				(font
					(size 1.27 1.27)
				)
				(justify mirror)
			)
		)
		(property "Value" "SC10U16V5KX-7-GP-U"
			(at 0.0762 -6.1214 180)
			(unlocked yes)
			(layer "B.Fab")
			(hide yes)
			(effects
				(font
					(size 1.016 1.016)
					(thickness 0.1524)
				)
				(justify mirror)
			)
		)
		(property "Device Type" "C805H58"
			(at 0.0762 -8.1534 180)
			(unlocked yes)
			(layer "B.Fab")
			(hide yes)
			(effects
				(font
					(size 1.016 1.016)
					(thickness 0.1524)
				)
				(justify mirror)
			)
		)
		(duplicate_pad_numbers_are_jumpers no)
		(fp_line
			(start -0.635 0)
			(end 0.635 0)
			(stroke
				(width 0.508)
				(type default)
			)
			(layer "B.SilkS")
		)
		(fp_rect
			(start 0.9652 1.778)
			(end -0.9652 -1.778)
			(stroke
				(width 0)
				(type default)
			)
			(fill no)
			(layer "B.CrtYd")
		)
		(fp_poly
			(pts
				(xy 0.9652 -1.778) (xy -0.9652 -1.778) (xy -0.9652 1.778) (xy 0.9652 1.778)
			)
			(stroke
				(width 0)
				(type default)
			)
			(fill no)
			(layer "B.Fab")
		)
		(pad "1" smd rect
			(at 0 -0.9652)
			(size 1.397 1.143)
			(layers "B.Cu" "B.Mask" "B.Paste")
			(net "P12V_B_4_VIN_U34")
		)
		(pad "2" smd rect
			(at 0 0.9652)
			(size 1.397 1.143)
			(layers "B.Cu" "B.Mask" "B.Paste")
			(net "GND")
		)
	)
	(footprint ""
		(layer "B.Cu")
		(at 444.820802 -220.09735 90)
		(property "Reference" "L5"
			(at 0 0 90)
			(layer "B.SilkS")
			(hide yes)
			(effects
				(font
					(size 1.27 1.27)
				)
				(justify mirror)
			)
		)
		(property "Value" "BLM21PG220SN1DGP"
			(at -0.0254 -5.6896 90)
			(unlocked yes)
			(layer "B.Fab")
			(hide yes)
			(effects
				(font
					(size 1.016 1.016)
					(thickness 0.1524)
				)
				(justify mirror)
			)
		)
		(property "Device Type" "L20125H42"
			(at -0.0254 -7.5946 90)
			(unlocked yes)
			(layer "B.Fab")
			(hide yes)
			(effects
				(font
					(size 1.016 1.016)
					(thickness 0.1524)
				)
				(justify mirror)
			)
		)
		(duplicate_pad_numbers_are_jumpers no)
		(fp_line
			(start 0.9144 -1.7018)
			(end 0.9144 1.7018)
			(stroke
				(width 0.1524)
				(type default)
			)
			(layer "B.SilkS")
		)
		(fp_line
			(start -0.9144 -1.7018)
			(end 0.9144 -1.7018)
			(stroke
				(width 0.1524)
				(type default)
			)
			(layer "B.SilkS")
		)
		(fp_line
			(start 0.9144 1.7018)
			(end -0.9144 1.7018)
			(stroke
				(width 0.1524)
				(type default)
			)
			(layer "B.SilkS")
		)
		(fp_line
			(start -0.9144 1.7018)
			(end -0.9144 -1.7018)
			(stroke
				(width 0.1524)
				(type default)
			)
			(layer "B.SilkS")
		)
		(fp_rect
			(start 1.0033 1.778)
			(end -1.0033 -1.778)
			(stroke
				(width 0)
				(type default)
			)
			(fill no)
			(layer "B.CrtYd")
		)
		(fp_poly
			(pts
				(xy 1.0033 -1.778) (xy -1.0033 -1.778) (xy -1.0033 1.778) (xy 1.0033 1.778)
			)
			(stroke
				(width 0)
				(type default)
			)
			(fill no)
			(layer "B.Fab")
		)
		(pad "1" smd rect
			(at 0 -0.9652 270)
			(size 1.397 1.143)
			(layers "B.Cu" "B.Mask" "B.Paste")
			(net "P12V_B")
		)
		(pad "2" smd rect
			(at 0 0.9652 270)
			(size 1.397 1.143)
			(layers "B.Cu" "B.Mask" "B.Paste")
			(net "P12V_B_3_VIN_U33")
		)
	)
)
